(kicad_pcb
	(version 20260206)
	(generator "pcbnew")
	(generator_version "10.0")
	(general
		(thickness 1.5755)
		(legacy_teardrops no)
	)
	(paper "A4")
	(title_block
		(title "gnss-rcb-f9t — GPS_MODULE_ZED-F9T.PcbDoc")
		(comment 1 "Time Appliance Project (Time Card) / footprints 14-20 of 44")
	)
	(layers
		(0 "F.Cu" signal "Top Layer")
		(4 "In1.Cu" signal "Int1 (GND)")
		(6 "In2.Cu" signal "Int2 (GND)")
		(2 "B.Cu" signal "Bottom Layer")
		(9 "F.Adhes" user "F.Adhesive")
		(11 "B.Adhes" user "B.Adhesive")
		(13 "F.Paste" user "Top Paste")
		(15 "B.Paste" user "Bottom Paste")
		(5 "F.SilkS" user "Top Overlay")
		(7 "B.SilkS" user "Bottom Overlay")
		(1 "F.Mask" user "Top Solder")
		(3 "B.Mask" user "Bottom Solder")
		(17 "Dwgs.User" user "User.Drawings")
		(19 "Cmts.User" user "User.Comments")
		(21 "Eco1.User" user "User.Eco1")
		(23 "Eco2.User" user "User.Eco2")
		(25 "Edge.Cuts" user)
		(27 "Margin" user)
		(31 "F.CrtYd" user "Top Courtyard")
		(29 "B.CrtYd" user "Bottom Courtyard")
		(35 "F.Fab" user "Top Component Outline")
		(33 "B.Fab" user "Bottom Component Outline")
	)
	(footprint "Vault:FP-0402-L_1_0_0_05-W_0_5-IPC_B"
		(layer "F.Cu")
		(at 134.3461 101.1657 180)
		(property "Reference" "C8"
			(at -0.15 1.49573 0)
			(unlocked yes)
			(layer "F.SilkS")
			(effects
				(font
					(size 0.8 0.8)
					(thickness 0.15)
				)
			)
		)
		(property "Value" "100nF"
			(at -2.95799 -2.352802 0)
			(unlocked yes)
			(layer "F.SilkS")
			(hide yes)
			(effects
				(font
					(size 1.524 1.524)
					(thickness 0.254)
				)
			)
		)
		(sheetname "Antenna_Supervisor")
		(sheetfile "Antenna_Supervisor.kicad_sch")
		(duplicate_pad_numbers_are_jumpers no)
		(fp_line
			(start 0.73623 0.68624)
			(end -0.73624 0.68624)
			(stroke
				(width 0.2)
				(type solid)
			)
			(layer "F.SilkS")
		)
		(fp_line
			(start 0.73623 -0.68624)
			(end -0.73624 -0.68624)
			(stroke
				(width 0.2)
				(type solid)
			)
			(layer "F.SilkS")
		)
		(fp_line
			(start 0.88623 0.43624)
			(end -0.88624 0.43624)
			(stroke
				(width 0.2)
				(type solid)
			)
			(layer "F.CrtYd")
		)
		(fp_line
			(start 0.88623 -0.43624)
			(end 0.88623 0.43624)
			(stroke
				(width 0.2)
				(type solid)
			)
			(layer "F.CrtYd")
		)
		(fp_line
			(start 0.88623 -0.43624)
			(end -0.88624 -0.43624)
			(stroke
				(width 0.2)
				(type solid)
			)
			(layer "F.CrtYd")
		)
		(fp_line
			(start -0.88624 -0.43624)
			(end -0.88624 0.43624)
			(stroke
				(width 0.2)
				(type solid)
			)
			(layer "F.CrtYd")
		)
		(fp_line
			(start 0.88623 0.43624)
			(end -0.88624 0.43624)
			(stroke
				(width 0.2)
				(type solid)
			)
			(layer "F.Fab")
		)
		(fp_line
			(start 0.88623 -0.43624)
			(end 0.88623 0.43624)
			(stroke
				(width 0.2)
				(type solid)
			)
			(layer "F.Fab")
		)
		(fp_line
			(start 0.88623 -0.43624)
			(end -0.88624 -0.43624)
			(stroke
				(width 0.2)
				(type solid)
			)
			(layer "F.Fab")
		)
		(fp_line
			(start 0.5 0)
			(end -0.5 0)
			(stroke
				(width 0.1)
				(type solid)
			)
			(layer "F.Fab")
		)
		(fp_line
			(start 0 -0.5)
			(end 0 0.5)
			(stroke
				(width 0.1)
				(type solid)
			)
			(layer "F.Fab")
		)
		(fp_line
			(start -0.88624 -0.43624)
			(end -0.88624 0.43624)
			(stroke
				(width 0.2)
				(type solid)
			)
			(layer "F.Fab")
		)
		(fp_text user "${REFERENCE}"
			(at 0.5842 0.94493 360)
			(unlocked yes)
			(layer "F.Fab")
			(effects
				(font
					(face "Arial")
					(size 0.63 0.63)
					(thickness 0.1)
				)
				(justify left bottom)
			)
		)
		(pad "1" smd rect
			(at -0.42856 0 180)
			(size 0.61535 0.57247)
			(layers "F.Cu" "F.Mask" "F.Paste")
			(net "RF_IN")
			(solder_mask_margin 0)
			(solder_paste_margin 0)
		)
		(pad "2" smd rect
			(at 0.42856 0 180)
			(size 0.61535 0.57247)
			(layers "F.Cu" "F.Mask" "F.Paste")
			(net "RF_ANT")
			(solder_mask_margin 0)
			(solder_paste_margin 0)
		)
	)
	(footprint "Vault:FP-RMCF0402-IPC_C"
		(layer "F.Cu")
		(at 132.4411 109.1921 180)
		(property "Reference" "R11"
			(at -0.632605 -1.55227 0)
			(unlocked yes)
			(layer "F.SilkS")
			(effects
				(font
					(size 0.8 0.8)
					(thickness 0.15)
				)
			)
		)
		(property "Value" "100k"
			(at -2.19628 -2.352802 0)
			(unlocked yes)
			(layer "F.SilkS")
			(hide yes)
			(effects
				(font
					(size 1.524 1.524)
					(thickness 0.254)
				)
			)
		)
		(sheetname "Antenna_Supervisor")
		(sheetfile "Antenna_Supervisor.kicad_sch")
		(duplicate_pad_numbers_are_jumpers no)
		(fp_line
			(start 0.65606 0.675)
			(end -0.65607 0.675)
			(stroke
				(width 0.2)
				(type solid)
			)
			(layer "F.SilkS")
		)
		(fp_line
			(start 0.65606 -0.675)
			(end -0.65607 -0.675)
			(stroke
				(width 0.2)
				(type solid)
			)
			(layer "F.SilkS")
		)
		(fp_line
			(start 0.75606 0.375)
			(end -0.75607 0.375)
			(stroke
				(width 0.2)
				(type solid)
			)
			(layer "F.CrtYd")
		)
		(fp_line
			(start 0.75606 -0.375)
			(end 0.75606 0.375)
			(stroke
				(width 0.2)
				(type solid)
			)
			(layer "F.CrtYd")
		)
		(fp_line
			(start 0.75606 -0.375)
			(end -0.75607 -0.375)
			(stroke
				(width 0.2)
				(type solid)
			)
			(layer "F.CrtYd")
		)
		(fp_line
			(start -0.75607 -0.375)
			(end -0.75607 0.375)
			(stroke
				(width 0.2)
				(type solid)
			)
			(layer "F.CrtYd")
		)
		(fp_line
			(start 0.75606 0.375)
			(end -0.75607 0.375)
			(stroke
				(width 0.2)
				(type solid)
			)
			(layer "F.Fab")
		)
		(fp_line
			(start 0.75606 -0.375)
			(end 0.75606 0.375)
			(stroke
				(width 0.2)
				(type solid)
			)
			(layer "F.Fab")
		)
		(fp_line
			(start 0.75606 -0.375)
			(end -0.75607 -0.375)
			(stroke
				(width 0.2)
				(type solid)
			)
			(layer "F.Fab")
		)
		(fp_line
			(start 0.5 0)
			(end -0.5 0)
			(stroke
				(width 0.1)
				(type solid)
			)
			(layer "F.Fab")
		)
		(fp_line
			(start 0 -0.5)
			(end 0 0.5)
			(stroke
				(width 0.1)
				(type solid)
			)
			(layer "F.Fab")
		)
		(fp_line
			(start -0.75607 -0.375)
			(end -0.75607 0.375)
			(stroke
				(width 0.2)
				(type solid)
			)
			(layer "F.Fab")
		)
		(fp_text user "${REFERENCE}"
			(at 0.4826 -1.9105 360)
			(unlocked yes)
			(layer "F.Fab")
			(effects
				(font
					(face "Arial")
					(size 0.63 0.63)
					(thickness 0.1)
				)
				(justify left bottom)
			)
		)
		(pad "1" smd rect
			(at -0.36554 0 180)
			(size 0.58106 0.47247)
			(layers "F.Cu" "F.Mask" "F.Paste")
			(net "GND")
			(solder_mask_margin 0)
			(solder_paste_margin 0)
		)
		(pad "2" smd rect
			(at 0.36553 0 180)
			(size 0.58106 0.47247)
			(layers "F.Cu" "F.Mask" "F.Paste")
			(net "NetR10_1")
			(solder_mask_margin 0)
			(solder_paste_margin 0)
		)
	)
	(footprint "Vault:DCU0008A_N"
		(layer "F.Cu")
		(at 134.7271 106.0679)
		(property "Reference" "U3"
			(at -0.4088 2.00947 0)
			(unlocked yes)
			(layer "F.SilkS")
			(effects
				(font
					(size 0.8 0.8)
					(thickness 0.15)
				)
			)
		)
		(property "Value" "SN74LVC3G07DCUR"
			(at 9.432485 2.911602 0)
			(unlocked yes)
			(layer "F.SilkS")
			(hide yes)
			(effects
				(font
					(size 1.524 1.524)
					(thickness 0.254)
				)
			)
		)
		(sheetname "Antenna_Supervisor")
		(sheetfile "Antenna_Supervisor.kicad_sch")
		(duplicate_pad_numbers_are_jumpers no)
		(fp_line
			(start -0.8 -1.05)
			(end 0.8 -1.05)
			(stroke
				(width 0.2)
				(type solid)
			)
			(layer "F.SilkS")
		)
		(fp_line
			(start -0.8 1.05)
			(end -0.8 -1.05)
			(stroke
				(width 0.2)
				(type solid)
			)
			(layer "F.SilkS")
		)
		(fp_line
			(start -0.8 1.05)
			(end 0.8 1.05)
			(stroke
				(width 0.2)
				(type solid)
			)
			(layer "F.SilkS")
		)
		(fp_line
			(start 0.8 1.05)
			(end 0.8 -1.05)
			(stroke
				(width 0.2)
				(type solid)
			)
			(layer "F.SilkS")
		)
		(fp_circle
			(center -1.6 -1.45)
			(end -1.6 -1.575)
			(stroke
				(width 0.25)
				(type solid)
			)
			(fill no)
			(layer "F.SilkS")
		)
		(fp_line
			(start -2.225 -1.3)
			(end 2.225 -1.3)
			(stroke
				(width 0.05)
				(type solid)
			)
			(layer "F.CrtYd")
		)
		(fp_line
			(start -2.225 1.3)
			(end -2.225 -1.3)
			(stroke
				(width 0.05)
				(type solid)
			)
			(layer "F.CrtYd")
		)
		(fp_line
			(start -2.225 1.3)
			(end 2.225 1.3)
			(stroke
				(width 0.05)
				(type solid)
			)
			(layer "F.CrtYd")
		)
		(fp_line
			(start -0.5 0)
			(end 0.5 0)
			(stroke
				(width 0.1)
				(type solid)
			)
			(layer "F.CrtYd")
		)
		(fp_line
			(start 0 0.5)
			(end 0 -0.5)
			(stroke
				(width 0.1)
				(type solid)
			)
			(layer "F.CrtYd")
		)
		(fp_line
			(start 2.225 1.3)
			(end 2.225 -1.3)
			(stroke
				(width 0.05)
				(type solid)
			)
			(layer "F.CrtYd")
		)
		(pad "1" smd roundrect
			(at -1.6 -0.75 90)
			(size 0.3 0.8)
			(layers "F.Cu" "F.Mask" "F.Paste")
			(roundrect_rratio 0.165)
			(net "NetU3_1")
		)
		(pad "2" smd roundrect
			(at -1.6 -0.25 90)
			(size 0.3 0.8)
			(layers "F.Cu" "F.Mask" "F.Paste")
			(roundrect_rratio 0.165)
			(net "NetQ1_1")
		)
		(pad "3" smd roundrect
			(at -1.6 0.25 90)
			(size 0.3 0.8)
			(layers "F.Cu" "F.Mask" "F.Paste")
			(roundrect_rratio 0.165)
			(net "NetC10_1")
		)
		(pad "4" smd roundrect
			(at -1.6 0.75 90)
			(size 0.3 0.8)
			(layers "F.Cu" "F.Mask" "F.Paste")
			(roundrect_rratio 0.165)
			(net "GND")
		)
		(pad "5" smd roundrect
			(at 1.6 0.75 90)
			(size 0.3 0.8)
			(layers "F.Cu" "F.Mask" "F.Paste")
			(roundrect_rratio 0.165)
			(net "ANT_SHORT_N")
		)
		(pad "6" smd roundrect
			(at 1.6 0.25 90)
			(size 0.3 0.8)
			(layers "F.Cu" "F.Mask" "F.Paste")
			(roundrect_rratio 0.165)
			(net "ANT_OFF")
		)
		(pad "7" smd roundrect
			(at 1.6 -0.25 90)
			(size 0.3 0.8)
			(layers "F.Cu" "F.Mask" "F.Paste")
			(roundrect_rratio 0.165)
			(net "ANT_DET")
		)
		(pad "8" smd roundrect
			(at 1.6 -0.75 90)
			(size 0.3 0.8)
			(layers "F.Cu" "F.Mask" "F.Paste")
			(roundrect_rratio 0.165)
			(net "VCC")
		)
	)
	(footprint "Vault:CAPC1005X055N"
		(layer "F.Cu")
		(at 156.4441 104.2391)
		(property "Reference" "C4"
			(at 2.055 0.02827 0)
			(unlocked yes)
			(layer "F.SilkS")
			(effects
				(font
					(size 0.8 0.8)
					(thickness 0.15)
				)
			)
		)
		(property "Value" "Murata_GRM155R61E105KA12D"
			(at 17.863025 2.073402 0)
			(unlocked yes)
			(layer "F.SilkS")
			(hide yes)
			(effects
				(font
					(size 1.524 1.524)
					(thickness 0.254)
				)
			)
		)
		(sheetname "ZED-F9T")
		(sheetfile "ZED-F9T.kicad_sch")
		(duplicate_pad_numbers_are_jumpers no)
		(fp_line
			(start -0.95 -0.5)
			(end 0.95 -0.5)
			(stroke
				(width 0.1)
				(type solid)
			)
			(layer "F.CrtYd")
		)
		(fp_line
			(start -0.95 0.5)
			(end -0.95 -0.5)
			(stroke
				(width 0.1)
				(type solid)
			)
			(layer "F.CrtYd")
		)
		(fp_line
			(start -0.95 0.5)
			(end 0.95 0.5)
			(stroke
				(width 0.1)
				(type solid)
			)
			(layer "F.CrtYd")
		)
		(fp_line
			(start 0.95 0.5)
			(end 0.95 -0.5)
			(stroke
				(width 0.1)
				(type solid)
			)
			(layer "F.CrtYd")
		)
		(fp_line
			(start -0.5 -0.25)
			(end 0.5 -0.25)
			(stroke
				(width 0.05)
				(type solid)
			)
			(layer "F.Fab")
		)
		(fp_line
			(start -0.5 0.25)
			(end -0.5 -0.25)
			(stroke
				(width 0.05)
				(type solid)
			)
			(layer "F.Fab")
		)
		(fp_line
			(start -0.5 0.25)
			(end 0.5 0.25)
			(stroke
				(width 0.05)
				(type solid)
			)
			(layer "F.Fab")
		)
		(fp_line
			(start 0.5 0.25)
			(end 0.5 -0.25)
			(stroke
				(width 0.05)
				(type solid)
			)
			(layer "F.Fab")
		)
		(fp_text_box "${REFERENCE}"
			(start -1.09004 -0.20727)
			(end 1.09004 0.20726)
			(margins 0 0 0 0)
			(layer "F.Fab")
			(effects
				(font
					(face "Arial")
					(size 0.315 0.315)
					(thickness 0.254)
				)
				(justify top)
			)
			(border no)
			(stroke
				(width 0.1)
				(type default)
			)
			(knockout no)
		)
		(pad "1" smd rect
			(at -0.46 0)
			(size 0.6 0.62)
			(layers "F.Cu" "F.Mask" "F.Paste")
			(net "VCC")
			(solder_mask_margin 0.05)
			(solder_paste_margin 0)
		)
		(pad "2" smd rect
			(at 0.46 0)
			(size 0.6 0.62)
			(layers "F.Cu" "F.Mask" "F.Paste")
			(net "GND")
			(solder_mask_margin 0.05)
			(solder_paste_margin 0)
		)
	)
	(footprint "Vault:FP-RMCF0402-IPC_C"
		(layer "F.Cu")
		(at 167.7807 117.55363 -90)
		(property "Reference" "R8"
			(at 1.54734 -0.1418 0)
			(unlocked yes)
			(layer "F.SilkS")
			(effects
				(font
					(size 0.8 0.8)
					(thickness 0.15)
				)
			)
		)
		(property "Value" "10k"
			(at 2.352802 -1.434525 0)
			(unlocked yes)
			(layer "F.SilkS")
			(hide yes)
			(effects
				(font
					(size 1.524 1.524)
					(thickness 0.254)
				)
			)
		)
		(sheetname "ZED-F9T")
		(sheetfile "ZED-F9T.kicad_sch")
		(duplicate_pad_numbers_are_jumpers no)
		(fp_line
			(start 0.65607 0.675)
			(end -0.65607 0.675)
			(stroke
				(width 0.2)
				(type solid)
			)
			(layer "F.SilkS")
		)
		(fp_line
			(start 0.65607 -0.675)
			(end -0.65607 -0.675)
			(stroke
				(width 0.2)
				(type solid)
			)
			(layer "F.SilkS")
		)
		(fp_line
			(start -0.75606 0.375)
			(end -0.75606 -0.375)
			(stroke
				(width 0.2)
				(type solid)
			)
			(layer "F.CrtYd")
		)
		(fp_line
			(start 0.75607 0.375)
			(end -0.75606 0.375)
			(stroke
				(width 0.2)
				(type solid)
			)
			(layer "F.CrtYd")
		)
		(fp_line
			(start 0.75607 0.375)
			(end 0.75607 -0.375)
			(stroke
				(width 0.2)
				(type solid)
			)
			(layer "F.CrtYd")
		)
		(fp_line
			(start 0.75607 -0.375)
			(end -0.75606 -0.375)
			(stroke
				(width 0.2)
				(type solid)
			)
			(layer "F.CrtYd")
		)
		(fp_line
			(start 0 0.5)
			(end 0 -0.5)
			(stroke
				(width 0.1)
				(type solid)
			)
			(layer "F.Fab")
		)
		(fp_line
			(start -0.75606 0.375)
			(end -0.75606 -0.375)
			(stroke
				(width 0.2)
				(type solid)
			)
			(layer "F.Fab")
		)
		(fp_line
			(start 0.75607 0.375)
			(end -0.75606 0.375)
			(stroke
				(width 0.2)
				(type solid)
			)
			(layer "F.Fab")
		)
		(fp_line
			(start 0.75607 0.375)
			(end 0.75607 -0.375)
			(stroke
				(width 0.2)
				(type solid)
			)
			(layer "F.Fab")
		)
		(fp_line
			(start 0.5 0)
			(end -0.5 0)
			(stroke
				(width 0.1)
				(type solid)
			)
			(layer "F.Fab")
		)
		(fp_line
			(start 0.75607 -0.375)
			(end -0.75606 -0.375)
			(stroke
				(width 0.2)
				(type solid)
			)
			(layer "F.Fab")
		)
		(fp_text user "${REFERENCE}"
			(at -0.00001 0.09648 270)
			(unlocked yes)
			(layer "F.Fab")
			(effects
				(font
					(face "Arial")
					(size 0.63 0.63)
					(thickness 0.1)
				)
				(justify left bottom)
			)
		)
		(pad "1" smd rect
			(at -0.36553 0 270)
			(size 0.58106 0.47247)
			(layers "F.Cu" "F.Mask" "F.Paste")
			(net "GND")
			(solder_mask_margin 0)
			(solder_paste_margin 0)
		)
		(pad "2" smd rect
			(at 0.36554 0 270)
			(size 0.58106 0.47247)
			(layers "F.Cu" "F.Mask" "F.Paste")
			(net "NetDS3_K")
			(solder_mask_margin 0)
			(solder_paste_margin 0)
		)
	)
	(footprint "Vault:LEDS160X80X110-2N_LXFM0603-GR"
		(layer "F.Cu")
		(at 165.7577 116.6597 90)
		(property "Reference" "DS2"
			(at 2.77425 0.62377 0)
			(unlocked yes)
			(layer "F.SilkS")
			(effects
				(font
					(size 0.8 0.8)
					(thickness 0.15)
				)
			)
		)
		(property "Value" "Lumex_SML-LXFM0603SUGCTR"
			(at -3.318002 17.78687 0)
			(unlocked yes)
			(layer "F.SilkS")
			(hide yes)
			(effects
				(font
					(size 1.524 1.524)
					(thickness 0.254)
				)
			)
		)
		(sheetname "ZED-F9T")
		(sheetfile "ZED-F9T.kicad_sch")
		(duplicate_pad_numbers_are_jumpers no)
		(fp_line
			(start -1.6 -0.3)
			(end -1.6 0.3)
			(stroke
				(width 0.1)
				(type solid)
			)
			(layer "F.SilkS")
		)
		(fp_line
			(start 1.7 -0.7)
			(end 1.7 0.7)
			(stroke
				(width 0.1)
				(type solid)
			)
			(layer "F.CrtYd")
		)
		(fp_line
			(start -1.7 -0.7)
			(end 1.7 -0.7)
			(stroke
				(width 0.1)
				(type solid)
			)
			(layer "F.CrtYd")
		)
		(fp_line
			(start -1.7 -0.7)
			(end -1.7 0.7)
			(stroke
				(width 0.1)
				(type solid)
			)
			(layer "F.CrtYd")
		)
		(fp_line
			(start -1.7 0.7)
			(end 1.7 0.7)
			(stroke
				(width 0.1)
				(type solid)
			)
			(layer "F.CrtYd")
		)
		(fp_line
			(start 0.80017 -0.40012)
			(end 0.80017 0.39984)
			(stroke
				(width 0.05)
				(type solid)
			)
			(layer "F.Fab")
		)
		(fp_line
			(start -0.79991 -0.40012)
			(end 0.80017 -0.40012)
			(stroke
				(width 0.05)
				(type solid)
			)
			(layer "F.Fab")
		)
		(fp_line
			(start -0.79991 -0.40012)
			(end -0.79991 0.39984)
			(stroke
				(width 0.05)
				(type solid)
			)
			(layer "F.Fab")
		)
		(fp_line
			(start -0.1 -0.3)
			(end -0.1 0.3)
			(stroke
				(width 0.05)
				(type solid)
			)
			(layer "F.Fab")
		)
		(fp_line
			(start 0.1 -0.2)
			(end -0.1 0)
			(stroke
				(width 0.05)
				(type solid)
			)
			(layer "F.Fab")
		)
		(fp_line
			(start 0.1 -0.2)
			(end 0.1 0.2)
			(stroke
				(width 0.05)
				(type solid)
			)
			(layer "F.Fab")
		)
		(fp_line
			(start -0.1 0)
			(end 0.1 0.2)
			(stroke
				(width 0.05)
				(type solid)
			)
			(layer "F.Fab")
		)
		(fp_line
			(start -0.79991 0.39984)
			(end 0.80017 0.39984)
			(stroke
				(width 0.05)
				(type solid)
			)
			(layer "F.Fab")
		)
		(fp_text_box "${REFERENCE}"
			(start -2.76576 -0.52568)
			(end 2.76577 0.52568)
			(margins 0 0 0 0)
			(layer "F.Fab")
			(effects
				(font
					(face "Arial")
					(size 0.8001 0.8001)
					(thickness 0.254)
				)
				(justify top)
			)
			(border no)
			(stroke
				(width 0.1)
				(type default)
			)
			(knockout no)
		)
		(pad "A" smd rect
			(at 0.825 0 90)
			(size 0.8 0.8)
			(layers "F.Cu" "F.Mask" "F.Paste")
			(net "VCC")
			(solder_mask_margin 0.05)
			(solder_paste_margin 0)
		)
		(pad "K" smd rect
			(at -0.825 0 90)
			(size 0.8 0.8)
			(layers "F.Cu" "F.Mask" "F.Paste")
			(net "NetDS2_K")
			(solder_mask_margin 0.05)
			(solder_paste_margin 0)
		)
	)
	(footprint "Vault:TP001V_SMT_100DIA"
		(layer "F.Cu")
		(at 151.9991 95.0951 90)
		(property "Reference" "TP4"
			(at 2.563 0.23147 90)
			(unlocked yes)
			(layer "F.SilkS")
			(effects
				(font
					(size 0.8 0.8)
					(thickness 0.15)
				)
			)
		)
		(property "Value" "SMT_100DIA"
			(at -2.124202 7.0716 0)
			(unlocked yes)
			(layer "F.SilkS")
			(hide yes)
			(effects
				(font
					(size 1.524 1.524)
					(thickness 0.254)
				)
			)
		)
		(sheetname "ZED-F9T")
		(sheetfile "ZED-F9T.kicad_sch")
		(duplicate_pad_numbers_are_jumpers no)
		(pad "1" smd circle
			(at 0 0 90)
			(size 1 1)
			(layers "F.Cu" "F.Mask" "F.Paste")
			(net "NetTP4_1")
			(solder_mask_margin 0.05)
			(solder_paste_margin 0)
			(thermal_bridge_angle 90)
		)
	)
)
